# TIMECARD (Time Appliance Project (Time Card)) — schematic netlist excerpt (pin names and nets, part order shuffled) for the footprints in the layout excerpt that follows; sources: Cadence DE-HDL packaged netlist, KiCad conversion of R4006-B0001-02_R01.brd

C312  CAPACITOR  0.1UF 10V 10%  pkg SMC_0402R_H022  page 19 : \1\ = XP3R3V ; \2\ = SG
C314  CAPACITOR  10UF 6.3V 20%  pkg SMC_0402R_H022  page 26 : \1\ = XP3R3V_FPGA ; \2\ = SG

(kicad_pcb
	(version 20260206)
	(generator "pcbnew")
	(generator_version "10.0")
	(general
		(thickness 1.6)
		(legacy_teardrops no)
	)
	(paper "A4")
	(title_block
		(title "timecard-production-celestica-r4006 — R4006-B0001-02_R01.brd")
		(comment 1 "Time Appliance Project (Time Card) / footprints 529-530 of 1113")
	)
	(layers
		(0 "F.Cu" signal "TOP")
		(4 "In1.Cu" signal "L02_GND1")
		(6 "In2.Cu" signal "L03_SIG1")
		(8 "In3.Cu" signal "L04_GND2")
		(10 "In4.Cu" signal "L05_VCC1")
		(12 "In5.Cu" signal "L06_VCC2")
		(14 "In6.Cu" signal "L07_GND3")
		(16 "In7.Cu" signal "L08_SIG2")
		(18 "In8.Cu" signal "L09_GND4")
		(2 "B.Cu" signal "BOTTOM")
		(9 "F.Adhes" user "F.Adhesive")
		(11 "B.Adhes" user "B.Adhesive")
		(13 "F.Paste" user "Package Geometry/Pastemask Top")
		(15 "B.Paste" user "Package Geometry/Pastemask Bottom")
		(5 "F.SilkS" user "Ref Des/Silkscreen Top")
		(7 "B.SilkS" user "Ref Des/Silkscreen Bottom")
		(1 "F.Mask" user "Board Geometry/Soldermask Top")
		(3 "B.Mask" user "Board Geometry/Soldermask Bottom")
		(17 "Dwgs.User" user "User.Drawings")
		(19 "Cmts.User" user "User.Comments")
		(21 "Eco1.User" user "User.Eco1")
		(23 "Eco2.User" user "User.Eco2")
		(25 "Edge.Cuts" user "Board Geometry/Outline")
		(27 "Margin" user)
		(31 "F.CrtYd" user "Package Geometry/Place Bound Top")
		(29 "B.CrtYd" user "Package Geometry/Place Bound Bottom")
		(35 "F.Fab" user "Ref Des/Assembly Top")
		(33 "B.Fab" user "Ref Des/Assembly Bottom")
	)
	(footprint ""
		(layer "F.Cu")
		(at 18.161 -61.5442 90)
		(property "Reference" "C312"
			(at 0.1778 -0.97663 90)
			(unlocked yes)
			(layer "F.SilkS")
			(effects
				(font
					(size 0.7874 0.5842)
					(thickness 0.1524)
				)
			)
		)
		(property "Value" "VAL*"
			(at 0.0762 2.067306 90)
			(unlocked yes)
			(layer "F.Fab")
			(hide yes)
			(effects
				(font
					(size 0.7874 0.5842)
					(thickness 0.1524)
				)
			)
		)
		(property "Tolerance" "TOL*"
			(at 0.0762 3.032506 90)
			(unlocked yes)
			(layer "Cmts.User")
			(hide yes)
			(effects
				(font
					(size 0.7874 0.5842)
					(thickness 0.1524)
				)
			)
		)
		(property "User Part Number" "PARTNUM*"
			(at 0.1016 4.023106 90)
			(unlocked yes)
			(layer "Cmts.User")
			(hide yes)
			(effects
				(font
					(size 0.7874 0.5842)
					(thickness 0.1524)
				)
			)
		)
		(property "Device Type" "CAPACITOR-G105-0B104-CK,0.1UF,A"
			(at 0.0508 1.127506 90)
			(unlocked yes)
			(layer "F.Fab")
			(hide yes)
			(effects
				(font
					(size 0.7874 0.5842)
					(thickness 0.1524)
				)
			)
		)
		(duplicate_pad_numbers_are_jumpers no)
		(fp_line
			(start 1.143 -0.5588)
			(end -1.143 -0.5588)
			(stroke
				(width 0.1)
				(type default)
			)
			(layer "F.SilkS")
		)
		(fp_line
			(start -1.143 -0.5588)
			(end -1.143 0.5588)
			(stroke
				(width 0.1)
				(type default)
			)
			(layer "F.SilkS")
		)
		(fp_line
			(start 1.143 0.5588)
			(end 1.143 -0.5588)
			(stroke
				(width 0.1)
				(type default)
			)
			(layer "F.SilkS")
		)
		(fp_line
			(start -1.143 0.5588)
			(end 1.143 0.5588)
			(stroke
				(width 0.1)
				(type default)
			)
			(layer "F.SilkS")
		)
		(fp_poly
			(pts
				(xy -1.143 0.5588) (xy 1.143 0.5588) (xy 1.143 -0.5588) (xy -1.143 -0.5588)
			)
			(stroke
				(width 0)
				(type default)
			)
			(fill no)
			(layer "F.CrtYd")
		)
		(fp_line
			(start 0.508 -0.3048)
			(end -0.508 -0.3048)
			(stroke
				(width 0.1)
				(type default)
			)
			(layer "F.Fab")
		)
		(fp_line
			(start -0.508 -0.3048)
			(end -0.508 0.3048)
			(stroke
				(width 0.1)
				(type default)
			)
			(layer "F.Fab")
		)
		(fp_line
			(start 0.508 0.3048)
			(end 0.508 -0.3048)
			(stroke
				(width 0.1)
				(type default)
			)
			(layer "F.Fab")
		)
		(fp_line
			(start -0.508 0.3048)
			(end 0.508 0.3048)
			(stroke
				(width 0.1)
				(type default)
			)
			(layer "F.Fab")
		)
		(pad "1" smd rect
			(at -0.5334 0 90)
			(size 0.7112 0.6096)
			(layers "F.Cu" "F.Mask" "F.Paste")
			(net "XP3R3V")
		)
		(pad "2" smd rect
			(at 0.5334 0 90)
			(size 0.7112 0.6096)
			(layers "F.Cu" "F.Mask" "F.Paste")
			(net "SG")
		)
		(zone
			(layer "F.Cu")
			(hatch none 0.5)
			(connect_pads
				(clearance 0)
			)
			(min_thickness 0.25)
			(keepout
				(tracks not_allowed)
				(vias allowed)
				(pads allowed)
				(copperpour not_allowed)
				(footprints allowed)
			)
			(placement
				(enabled no)
				(sheetname "")
			)
			(fill
				(thermal_gap 0.5)
				(thermal_bridge_width 0.5)
				(island_removal_mode 0)
			)
			(polygon
				(pts
					(xy 18.4658 -61.468) (xy 18.4658 -61.6204) (xy 17.8562 -61.6204) (xy 17.8562 -61.468)
				)
			)
		)
		(zone
			(layer "F.Cu")
			(hatch none 0.5)
			(connect_pads
				(clearance 0)
			)
			(min_thickness 0.25)
			(keepout
				(tracks allowed)
				(vias not_allowed)
				(pads allowed)
				(copperpour not_allowed)
				(footprints allowed)
			)
			(placement
				(enabled no)
				(sheetname "")
			)
			(fill
				(thermal_gap 0.5)
				(thermal_bridge_width 0.5)
				(island_removal_mode 0)
			)
			(polygon
				(pts
					(xy 18.4658 -61.468) (xy 18.4658 -61.6204) (xy 17.8562 -61.6204) (xy 17.8562 -61.468)
				)
			)
		)
	)
	(footprint ""
		(layer "F.Cu")
		(at 111.125 -100.711)
		(property "Reference" "C314"
			(at 3.175 -3.13563 0)
			(unlocked yes)
			(layer "F.SilkS")
			(effects
				(font
					(size 0.7874 0.5842)
					(thickness 0.1524)
				)
			)
		)
		(property "Value" "VAL*"
			(at 0.0762 2.067306 0)
			(unlocked yes)
			(layer "F.Fab")
			(hide yes)
			(effects
				(font
					(size 0.7874 0.5842)
					(thickness 0.1524)
				)
			)
		)
		(property "Tolerance" "TOL*"
			(at 0.0762 3.032506 0)
			(unlocked yes)
			(layer "Cmts.User")
			(hide yes)
			(effects
				(font
					(size 0.7874 0.5842)
					(thickness 0.1524)
				)
			)
		)
		(property "User Part Number" "PARTNUM*"
			(at 0.1016 4.023106 0)
			(unlocked yes)
			(layer "Cmts.User")
			(hide yes)
			(effects
				(font
					(size 0.7874 0.5842)
					(thickness 0.1524)
				)
			)
		)
		(property "Device Type" "CAPACITOR-G105-0C106-BM,10UF,2A"
			(at 0.0508 1.127506 0)
			(unlocked yes)
			(layer "F.Fab")
			(hide yes)
			(effects
				(font
					(size 0.7874 0.5842)
					(thickness 0.1524)
				)
			)
		)
		(duplicate_pad_numbers_are_jumpers no)
		(fp_line
			(start -1.143 -0.5588)
			(end -1.143 0.5588)
			(stroke
				(width 0.1)
				(type default)
			)
			(layer "F.SilkS")
		)
		(fp_line
			(start -1.143 0.5588)
			(end 1.143 0.5588)
			(stroke
				(width 0.1)
				(type default)
			)
			(layer "F.SilkS")
		)
		(fp_line
			(start 1.143 -0.5588)
			(end -1.143 -0.5588)
			(stroke
				(width 0.1)
				(type default)
			)
			(layer "F.SilkS")
		)
		(fp_line
			(start 1.143 0.5588)
			(end 1.143 -0.5588)
			(stroke
				(width 0.1)
				(type default)
			)
			(layer "F.SilkS")
		)
		(fp_poly
			(pts
				(xy -1.143 0.5588) (xy 1.143 0.5588) (xy 1.143 -0.5588) (xy -1.143 -0.5588)
			)
			(stroke
				(width 0)
				(type default)
			)
			(fill no)
			(layer "F.CrtYd")
		)
		(fp_line
			(start -0.508 -0.3048)
			(end -0.508 0.3048)
			(stroke
				(width 0.1)
				(type default)
			)
			(layer "F.Fab")
		)
		(fp_line
			(start -0.508 0.3048)
			(end 0.508 0.3048)
			(stroke
				(width 0.1)
				(type default)
			)
			(layer "F.Fab")
		)
		(fp_line
			(start 0.508 -0.3048)
			(end -0.508 -0.3048)
			(stroke
				(width 0.1)
				(type default)
			)
			(layer "F.Fab")
		)
		(fp_line
			(start 0.508 0.3048)
			(end 0.508 -0.3048)
			(stroke
				(width 0.1)
				(type default)
			)
			(layer "F.Fab")
		)
		(pad "1" smd rect
			(at -0.5334 0)
			(size 0.7112 0.6096)
			(layers "F.Cu" "F.Mask" "F.Paste")
			(net "XP3R3V_FPGA")
		)
		(pad "2" smd rect
			(at 0.5334 0)
			(size 0.7112 0.6096)
			(layers "F.Cu" "F.Mask" "F.Paste")
			(net "SG")
		)
		(zone
			(layer "F.Cu")
			(hatch none 0.5)
			(connect_pads
				(clearance 0)
			)
			(min_thickness 0.25)
			(keepout
				(tracks not_allowed)
				(vias allowed)
				(pads allowed)
				(copperpour not_allowed)
				(footprints allowed)
			)
			(placement
				(enabled no)
				(sheetname "")
			)
			(fill
				(thermal_gap 0.5)
				(thermal_bridge_width 0.5)
				(island_removal_mode 0)
			)
			(polygon
				(pts
					(xy 111.0488 -100.4062) (xy 111.2012 -100.4062) (xy 111.2012 -101.0158) (xy 111.0488 -101.0158)
				)
			)
		)
		(zone
			(layer "F.Cu")
			(hatch none 0.5)
			(connect_pads
				(clearance 0)
			)
			(min_thickness 0.25)
			(keepout
				(tracks allowed)
				(vias not_allowed)
				(pads allowed)
				(copperpour not_allowed)
				(footprints allowed)
			)
			(placement
				(enabled no)
				(sheetname "")
			)
			(fill
				(thermal_gap 0.5)
				(thermal_bridge_width 0.5)
				(island_removal_mode 0)
			)
			(polygon
				(pts
					(xy 111.0488 -100.4062) (xy 111.2012 -100.4062) (xy 111.2012 -101.0158) (xy 111.0488 -101.0158)
				)
			)
		)
	)
)
